(kicad_pcb
	(version 20260206)
	(generator "pcbnew")
	(generator_version "10.0")
	(general
		(thickness 1.6)
		(legacy_teardrops no)
	)
	(paper "A4")
	(title_block
		(title "Wiwynn_Tioga_Pass_MB.brd")
		(comment 1 "Tioga Pass / footprints 4160-4167 of 4770")
	)
	(layers
		(0 "F.Cu" signal "TOP")
		(4 "In1.Cu" signal "L2GND")
		(6 "In2.Cu" signal "L3")
		(8 "In3.Cu" signal "L4GND")
		(10 "In4.Cu" signal "L5")
		(12 "In5.Cu" signal "L6GND")
		(14 "In6.Cu" signal "L7VCC")
		(16 "In7.Cu" signal "L8VCC")
		(18 "In8.Cu" signal "L9GND")
		(20 "In9.Cu" signal "L10")
		(22 "In10.Cu" signal "L11GND")
		(24 "In11.Cu" signal "L12")
		(26 "In12.Cu" signal "L13GND")
		(2 "B.Cu" signal "BOTTOM")
		(9 "F.Adhes" user "F.Adhesive")
		(11 "B.Adhes" user "B.Adhesive")
		(13 "F.Paste" user "Package Geometry/Pastemask Top")
		(15 "B.Paste" user "Package Geometry/Pastemask Bottom")
		(5 "F.SilkS" user "Ref Des/Silkscreen Top")
		(7 "B.SilkS" user "Ref Des/Silkscreen Bottom")
		(1 "F.Mask" user "Board Geometry/Soldermask Top")
		(3 "B.Mask" user "Board Geometry/Soldermask Bottom")
		(17 "Dwgs.User" user "User.Drawings")
		(19 "Cmts.User" user "User.Comments")
		(21 "Eco1.User" user "User.Eco1")
		(23 "Eco2.User" user "User.Eco2")
		(25 "Edge.Cuts" user "Board Geometry/Outline")
		(27 "Margin" user)
		(31 "F.CrtYd" user "Package Geometry/Place Bound Top")
		(29 "B.CrtYd" user "Package Geometry/Place Bound Bottom")
		(35 "F.Fab" user "Ref Des/Assembly Top")
		(33 "B.Fab" user "Ref Des/Assembly Bottom")
	)
	(footprint ""
		(layer "B.Cu")
		(at 459.73873 -18.55724)
		(property "Reference" "C2T6"
			(at 0 0 0)
			(layer "B.SilkS")
			(hide yes)
			(effects
				(font
					(size 1.27 1.27)
				)
				(justify mirror)
			)
		)
		(property "Value" ""
			(at 0 0 0)
			(layer "B.Fab")
			(effects
				(font
					(size 1.27 1.27)
				)
				(justify mirror)
			)
		)
		(duplicate_pad_numbers_are_jumpers no)
		(fp_rect
			(start 0.7239 -0.2159)
			(end -0.7239 1.9939)
			(stroke
				(width 0)
				(type default)
			)
			(fill no)
			(layer "B.CrtYd")
		)
		(fp_line
			(start -0.7239 -0.2159)
			(end 0.7239 -0.2159)
			(stroke
				(width 0.1)
				(type default)
			)
			(layer "B.Fab")
		)
		(fp_line
			(start -0.7239 1.9939)
			(end -0.7239 -0.2159)
			(stroke
				(width 0.1)
				(type default)
			)
			(layer "B.Fab")
		)
		(fp_line
			(start 0.7239 -0.2159)
			(end 0.7239 1.9939)
			(stroke
				(width 0.1)
				(type default)
			)
			(layer "B.Fab")
		)
		(fp_line
			(start 0.7239 1.9939)
			(end -0.7239 1.9939)
			(stroke
				(width 0.1)
				(type default)
			)
			(layer "B.Fab")
		)
		(pad "1" smd rect
			(at 0 0 180)
			(size 1.27 1.016)
			(layers "B.Cu" "B.Mask" "B.Paste")
			(net "P3V3_STBY")
		)
		(pad "2" smd rect
			(at 0 1.778 180)
			(size 1.27 1.016)
			(layers "B.Cu" "B.Mask" "B.Paste")
			(net "GND")
		)
		(zone
			(layer "B.Cu")
			(hatch none 0.5)
			(connect_pads
				(clearance 0)
			)
			(min_thickness 0.25)
			(keepout
				(tracks not_allowed)
				(vias allowed)
				(pads allowed)
				(copperpour not_allowed)
				(footprints allowed)
			)
			(placement
				(enabled no)
				(sheetname "")
			)
			(fill
				(thermal_gap 0.5)
				(thermal_bridge_width 0.5)
				(island_removal_mode 0)
			)
			(polygon
				(pts
					(xy 460.37373 -18.04924) (xy 459.10373 -18.04924) (xy 459.10373 -17.28724) (xy 460.37373 -17.28724)
				)
			)
		)
	)
	(footprint ""
		(layer "B.Cu")
		(at 19.177 -69.596 180)
		(property "Reference" "R9P30"
			(at 0 0 0)
			(layer "B.SilkS")
			(hide yes)
			(effects
				(font
					(size 1.27 1.27)
				)
				(justify mirror)
			)
		)
		(property "Value" ""
			(at 0 0 0)
			(layer "B.Fab")
			(effects
				(font
					(size 1.27 1.27)
				)
				(justify mirror)
			)
		)
		(duplicate_pad_numbers_are_jumpers no)
		(fp_rect
			(start -0.4953 -0.2032)
			(end 0.4953 1.6002)
			(stroke
				(width 0)
				(type default)
			)
			(fill no)
			(layer "B.CrtYd")
		)
		(fp_line
			(start 0.4953 1.6002)
			(end 0.4953 -0.2032)
			(stroke
				(width 0.1)
				(type default)
			)
			(layer "B.Fab")
		)
		(fp_line
			(start 0.4953 -0.2032)
			(end -0.4953 -0.2032)
			(stroke
				(width 0.1)
				(type default)
			)
			(layer "B.Fab")
		)
		(fp_line
			(start -0.4953 1.6002)
			(end 0.4953 1.6002)
			(stroke
				(width 0.1)
				(type default)
			)
			(layer "B.Fab")
		)
		(fp_line
			(start -0.4953 -0.2032)
			(end -0.4953 1.6002)
			(stroke
				(width 0.1)
				(type default)
			)
			(layer "B.Fab")
		)
		(pad "1" smd rect
			(at 0 0)
			(size 0.762 0.889)
			(layers "B.Cu" "B.Mask" "B.Paste")
			(net "P12V_PSU")
		)
		(pad "2" smd rect
			(at 0 1.397)
			(size 0.762 0.889)
			(layers "B.Cu" "B.Mask" "B.Paste")
			(net "P12V_HSC_VCC")
		)
		(zone
			(layer "B.Cu")
			(hatch none 0.5)
			(connect_pads
				(clearance 0)
			)
			(min_thickness 0.25)
			(keepout
				(tracks not_allowed)
				(vias allowed)
				(pads allowed)
				(copperpour not_allowed)
				(footprints allowed)
			)
			(placement
				(enabled no)
				(sheetname "")
			)
			(fill
				(thermal_gap 0.5)
				(thermal_bridge_width 0.5)
				(island_removal_mode 0)
			)
			(polygon
				(pts
					(xy 19.558 -70.0405) (xy 19.558 -70.5485) (xy 18.796 -70.5485) (xy 18.796 -70.0405)
				)
			)
		)
		(zone
			(layer "B.Cu")
			(hatch none 0.5)
			(connect_pads
				(clearance 0)
			)
			(min_thickness 0.25)
			(keepout
				(tracks allowed)
				(vias not_allowed)
				(pads allowed)
				(copperpour not_allowed)
				(footprints allowed)
			)
			(placement
				(enabled no)
				(sheetname "")
			)
			(fill
				(thermal_gap 0.5)
				(thermal_bridge_width 0.5)
				(island_removal_mode 0)
			)
			(polygon
				(pts
					(xy 19.558 -70.0405) (xy 19.558 -70.5485) (xy 18.796 -70.5485) (xy 18.796 -70.0405)
				)
			)
		)
	)
	(footprint ""
		(layer "B.Cu")
		(at 385.463034 -26.506932 90)
		(property "Reference" "C2T14"
			(at 0 0 90)
			(layer "B.SilkS")
			(hide yes)
			(effects
				(font
					(size 1.27 1.27)
				)
				(justify mirror)
			)
		)
		(property "Value" ""
			(at 0 0 90)
			(layer "B.Fab")
			(effects
				(font
					(size 1.27 1.27)
				)
				(justify mirror)
			)
		)
		(duplicate_pad_numbers_are_jumpers no)
		(fp_poly
			(pts
				(xy -0.3048 -0.1016) (xy -0.3048 0.9906) (xy 0.3048 0.9906) (xy 0.3048 -0.1016)
			)
			(stroke
				(width 0)
				(type default)
			)
			(fill no)
			(layer "B.CrtYd")
		)
		(fp_line
			(start 0.3048 -0.1016)
			(end 0.3048 0.9906)
			(stroke
				(width 0.1)
				(type default)
			)
			(layer "B.Fab")
		)
		(fp_line
			(start -0.3048 -0.1016)
			(end 0.3048 -0.1016)
			(stroke
				(width 0.1)
				(type default)
			)
			(layer "B.Fab")
		)
		(fp_line
			(start 0.3048 0.9906)
			(end -0.3048 0.9906)
			(stroke
				(width 0.1)
				(type default)
			)
			(layer "B.Fab")
		)
		(fp_line
			(start -0.3048 0.9906)
			(end -0.3048 -0.1016)
			(stroke
				(width 0.1)
				(type default)
			)
			(layer "B.Fab")
		)
		(pad "1" smd rect
			(at 0 0 270)
			(size 0.508 0.508)
			(layers "B.Cu" "B.Mask" "B.Paste")
			(net "P3E_PCH_M2_TX_C_DN<2>")
		)
		(pad "2" smd rect
			(at 0 0.889 270)
			(size 0.508 0.508)
			(layers "B.Cu" "B.Mask" "B.Paste")
			(net "P3E_PCH_M2_TX_DN<2>")
		)
		(zone
			(layer "B.Cu")
			(hatch none 0.5)
			(connect_pads
				(clearance 0)
			)
			(min_thickness 0.25)
			(keepout
				(tracks allowed)
				(vias not_allowed)
				(pads allowed)
				(copperpour not_allowed)
				(footprints allowed)
			)
			(placement
				(enabled no)
				(sheetname "")
			)
			(fill
				(thermal_gap 0.5)
				(thermal_bridge_width 0.5)
				(island_removal_mode 0)
			)
			(polygon
				(pts
					(xy 385.717034 -26.760932) (xy 385.717034 -26.252932) (xy 386.098034 -26.252932) (xy 386.098034 -26.760932)
				)
			)
		)
		(zone
			(layer "B.Cu")
			(hatch none 0.5)
			(connect_pads
				(clearance 0)
			)
			(min_thickness 0.25)
			(keepout
				(tracks not_allowed)
				(vias allowed)
				(pads allowed)
				(copperpour not_allowed)
				(footprints allowed)
			)
			(placement
				(enabled no)
				(sheetname "")
			)
			(fill
				(thermal_gap 0.5)
				(thermal_bridge_width 0.5)
				(island_removal_mode 0)
			)
			(polygon
				(pts
					(xy 386.098034 -26.760932) (xy 386.098034 -26.252932) (xy 385.717034 -26.252932) (xy 385.717034 -26.760932)
				)
			)
		)
	)
	(footprint ""
		(layer "B.Cu")
		(at 252.1585 -17.7546 -90)
		(property "Reference" "C5T10"
			(at -1.848866 0.752348 270)
			(unlocked yes)
			(layer "B.SilkS")
			(effects
				(font
					(size 1.27 0.9652)
					(thickness 0.1524)
				)
				(justify mirror)
			)
		)
		(property "Value" ""
			(at 0 0 90)
			(layer "B.Fab")
			(effects
				(font
					(size 1.27 1.27)
				)
				(justify mirror)
			)
		)
		(duplicate_pad_numbers_are_jumpers no)
		(fp_rect
			(start 0.500126 1.598422)
			(end -0.500126 -0.201422)
			(stroke
				(width 0)
				(type default)
			)
			(fill no)
			(layer "B.CrtYd")
		)
		(fp_line
			(start -0.500126 1.598422)
			(end 0.500126 1.598422)
			(stroke
				(width 0.1)
				(type default)
			)
			(layer "B.Fab")
		)
		(fp_line
			(start 0.500126 1.598422)
			(end 0.500126 -0.201422)
			(stroke
				(width 0.1)
				(type default)
			)
			(layer "B.Fab")
		)
		(fp_line
			(start -0.500126 -0.201422)
			(end -0.500126 1.598422)
			(stroke
				(width 0.1)
				(type default)
			)
			(layer "B.Fab")
		)
		(fp_line
			(start 0.500126 -0.201422)
			(end -0.500126 -0.201422)
			(stroke
				(width 0.1)
				(type default)
			)
			(layer "B.Fab")
		)
		(pad "1" smd rect
			(at 0 0 180)
			(size 0.889 0.9906)
			(layers "B.Cu" "B.Mask" "B.Paste")
			(net "PVDDQ_ABC")
		)
		(pad "2" smd rect
			(at 0 1.397 180)
			(size 0.889 0.9906)
			(layers "B.Cu" "B.Mask" "B.Paste")
			(net "GND")
		)
		(zone
			(layer "B.Cu")
			(hatch none 0.5)
			(connect_pads
				(clearance 0)
			)
			(min_thickness 0.25)
			(keepout
				(tracks not_allowed)
				(vias allowed)
				(pads allowed)
				(copperpour not_allowed)
				(footprints allowed)
			)
			(placement
				(enabled no)
				(sheetname "")
			)
			(fill
				(thermal_gap 0.5)
				(thermal_bridge_width 0.5)
				(island_removal_mode 0)
			)
			(polygon
				(pts
					(xy 251.206 -17.2593) (xy 251.714 -17.2593) (xy 251.714 -18.2499) (xy 251.206 -18.2499)
				)
			)
		)
		(zone
			(layer "B.Cu")
			(hatch none 0.5)
			(connect_pads
				(clearance 0)
			)
			(min_thickness 0.25)
			(keepout
				(tracks allowed)
				(vias not_allowed)
				(pads allowed)
				(copperpour not_allowed)
				(footprints allowed)
			)
			(placement
				(enabled no)
				(sheetname "")
			)
			(fill
				(thermal_gap 0.5)
				(thermal_bridge_width 0.5)
				(island_removal_mode 0)
			)
			(polygon
				(pts
					(xy 251.206 -17.2593) (xy 251.714 -17.2593) (xy 251.714 -18.2499) (xy 251.206 -18.2499)
				)
			)
		)
	)
	(footprint ""
		(layer "B.Cu")
		(at 391.56894 -152.00122 -90)
		(property "Reference" "R2L10"
			(at 0 0 90)
			(layer "B.SilkS")
			(hide yes)
			(effects
				(font
					(size 1.27 1.27)
				)
				(justify mirror)
			)
		)
		(property "Value" ""
			(at 0 0 90)
			(layer "B.Fab")
			(effects
				(font
					(size 1.27 1.27)
				)
				(justify mirror)
			)
		)
		(duplicate_pad_numbers_are_jumpers no)
		(fp_poly
			(pts
				(xy 0.2794 -0.1016) (xy -0.2794 -0.1016) (xy -0.2794 0.9906) (xy 0.2794 0.9906)
			)
			(stroke
				(width 0)
				(type default)
			)
			(fill no)
			(layer "B.CrtYd")
		)
		(fp_line
			(start -0.2794 0.9906)
			(end -0.2794 -0.1016)
			(stroke
				(width 0.1)
				(type default)
			)
			(layer "B.Fab")
		)
		(fp_line
			(start 0.2794 0.9906)
			(end -0.2794 0.9906)
			(stroke
				(width 0.1)
				(type default)
			)
			(layer "B.Fab")
		)
		(fp_line
			(start -0.2794 -0.1016)
			(end 0.2794 -0.1016)
			(stroke
				(width 0.1)
				(type default)
			)
			(layer "B.Fab")
		)
		(fp_line
			(start 0.2794 -0.1016)
			(end 0.2794 0.9906)
			(stroke
				(width 0.1)
				(type default)
			)
			(layer "B.Fab")
		)
		(pad "1" smd rect
			(at 0 0 90)
			(size 0.508 0.508)
			(layers "B.Cu" "B.Mask" "B.Paste")
			(net "VR_PVNN_PCH_VINSEN")
		)
		(pad "2" smd rect
			(at 0 0.889 90)
			(size 0.508 0.508)
			(layers "B.Cu" "B.Mask" "B.Paste")
			(net "GND")
		)
		(zone
			(layer "B.Cu")
			(hatch none 0.5)
			(connect_pads
				(clearance 0)
			)
			(min_thickness 0.25)
			(keepout
				(tracks not_allowed)
				(vias allowed)
				(pads allowed)
				(copperpour not_allowed)
				(footprints allowed)
			)
			(placement
				(enabled no)
				(sheetname "")
			)
			(fill
				(thermal_gap 0.5)
				(thermal_bridge_width 0.5)
				(island_removal_mode 0)
			)
			(polygon
				(pts
					(xy 390.93394 -151.74722) (xy 390.93394 -152.25522) (xy 391.31494 -152.25522) (xy 391.31494 -151.74722)
				)
			)
		)
		(zone
			(layer "B.Cu")
			(hatch none 0.5)
			(connect_pads
				(clearance 0)
			)
			(min_thickness 0.25)
			(keepout
				(tracks allowed)
				(vias not_allowed)
				(pads allowed)
				(copperpour not_allowed)
				(footprints allowed)
			)
			(placement
				(enabled no)
				(sheetname "")
			)
			(fill
				(thermal_gap 0.5)
				(thermal_bridge_width 0.5)
				(island_removal_mode 0)
			)
			(polygon
				(pts
					(xy 391.31494 -151.74722) (xy 391.31494 -152.25522) (xy 390.93394 -152.25522) (xy 390.93394 -151.74722)
				)
			)
		)
	)
	(footprint ""
		(layer "B.Cu")
		(at 382.176274 -153.328624)
		(property "Reference" "C3L29"
			(at 0 0 0)
			(layer "B.SilkS")
			(hide yes)
			(effects
				(font
					(size 1.27 1.27)
				)
				(justify mirror)
			)
		)
		(property "Value" "*"
			(at -1.1811 -2.8194 0)
			(unlocked yes)
			(layer "B.Fab")
			(hide yes)
			(effects
				(font
					(size 1.27 1.016)
					(thickness 0.1524)
				)
				(justify mirror)
			)
		)
		(property "Device Type" "SC1U10V2KX-4-GP_SMD-BCG6-SC1U1A"
			(at -1.1811 -4.3434 0)
			(unlocked yes)
			(layer "B.Fab")
			(hide yes)
			(effects
				(font
					(size 1.27 1.016)
					(thickness 0.1524)
				)
				(justify mirror)
			)
		)
		(duplicate_pad_numbers_are_jumpers no)
		(fp_rect
			(start 0.4318 0.9525)
			(end -0.4318 -0.9525)
			(stroke
				(width 0)
				(type default)
			)
			(fill no)
			(layer "B.CrtYd")
		)
		(fp_rect
			(start 0.4318 0.9525)
			(end -0.4318 -0.9525)
			(stroke
				(width 0)
				(type default)
			)
			(fill no)
			(layer "B.Fab")
		)
		(pad "1" smd custom
			(at 0 -0.4445 180)
			(size 0.1524 0.1524)
			(layers "B.Cu" "B.Mask" "B.Paste")
			(net "P5V_STBY")
			(options
				(clearance outline)
				(anchor circle)
			)
			(primitives
				(gr_poly
					(pts
						(arc
							(start 0.3048 0.2032)
							(mid 0.275042 0.275042)
							(end 0.2032 0.3048)
						)
						(arc
							(start -0.2032 0.3048)
							(mid -0.275042 0.275042)
							(end -0.3048 0.2032)
						)
						(arc
							(start -0.3048 -0.2032)
							(mid -0.275042 -0.275042)
							(end -0.2032 -0.3048)
						)
						(arc
							(start 0.2032 -0.3048)
							(mid 0.275042 -0.275042)
							(end 0.3048 -0.2032)
						)
					)
					(width 0)
					(fill yes)
				)
			)
		)
		(pad "2" smd custom
			(at 0 0.4445 180)
			(size 0.1524 0.1524)
			(layers "B.Cu" "B.Mask" "B.Paste")
			(net "GND")
			(options
				(clearance outline)
				(anchor circle)
			)
			(primitives
				(gr_poly
					(pts
						(arc
							(start 0.3048 0.2032)
							(mid 0.275042 0.275042)
							(end 0.2032 0.3048)
						)
						(arc
							(start -0.2032 0.3048)
							(mid -0.275042 0.275042)
							(end -0.3048 0.2032)
						)
						(arc
							(start -0.3048 -0.2032)
							(mid -0.275042 -0.275042)
							(end -0.2032 -0.3048)
						)
						(arc
							(start 0.2032 -0.3048)
							(mid 0.275042 -0.275042)
							(end 0.3048 -0.2032)
						)
					)
					(width 0)
					(fill yes)
				)
			)
		)
	)
	(footprint ""
		(layer "B.Cu")
		(at -0.889 -132.334)
		(property "Reference" "R9M9"
			(at 0 0 0)
			(layer "B.SilkS")
			(hide yes)
			(effects
				(font
					(size 1.27 1.27)
				)
				(justify mirror)
			)
		)
		(property "Value" ""
			(at 0 0 0)
			(layer "B.Fab")
			(effects
				(font
					(size 1.27 1.27)
				)
				(justify mirror)
			)
		)
		(duplicate_pad_numbers_are_jumpers no)
		(fp_poly
			(pts
				(xy 0.2794 -0.1016) (xy -0.2794 -0.1016) (xy -0.2794 0.9906) (xy 0.2794 0.9906)
			)
			(stroke
				(width 0)
				(type default)
			)
			(fill no)
			(layer "B.CrtYd")
		)
		(fp_line
			(start -0.2794 -0.1016)
			(end 0.2794 -0.1016)
			(stroke
				(width 0.1)
				(type default)
			)
			(layer "B.Fab")
		)
		(fp_line
			(start -0.2794 0.9906)
			(end -0.2794 -0.1016)
			(stroke
				(width 0.1)
				(type default)
			)
			(layer "B.Fab")
		)
		(fp_line
			(start 0.2794 -0.1016)
			(end 0.2794 0.9906)
			(stroke
				(width 0.1)
				(type default)
			)
			(layer "B.Fab")
		)
		(fp_line
			(start 0.2794 0.9906)
			(end -0.2794 0.9906)
			(stroke
				(width 0.1)
				(type default)
			)
			(layer "B.Fab")
		)
		(pad "1" smd rect
			(at 0 0 180)
			(size 0.508 0.508)
			(layers "B.Cu" "B.Mask" "B.Paste")
			(net "FM_PVDDQ_KLM_EN")
		)
		(pad "2" smd rect
			(at 0 0.889 180)
			(size 0.508 0.508)
			(layers "B.Cu" "B.Mask" "B.Paste")
			(net "VR_PVDDQ_KLM_VREN")
		)
		(zone
			(layer "B.Cu")
			(hatch none 0.5)
			(connect_pads
				(clearance 0)
			)
			(min_thickness 0.25)
			(keepout
				(tracks allowed)
				(vias not_allowed)
				(pads allowed)
				(copperpour not_allowed)
				(footprints allowed)
			)
			(placement
				(enabled no)
				(sheetname "")
			)
			(fill
				(thermal_gap 0.5)
				(thermal_bridge_width 0.5)
				(island_removal_mode 0)
			)
			(polygon
				(pts
					(xy -0.635 -132.08) (xy -1.143 -132.08) (xy -1.143 -131.699) (xy -0.635 -131.699)
				)
			)
		)
		(zone
			(layer "B.Cu")
			(hatch none 0.5)
			(connect_pads
				(clearance 0)
			)
			(min_thickness 0.25)
			(keepout
				(tracks not_allowed)
				(vias allowed)
				(pads allowed)
				(copperpour not_allowed)
				(footprints allowed)
			)
			(placement
				(enabled no)
				(sheetname "")
			)
			(fill
				(thermal_gap 0.5)
				(thermal_bridge_width 0.5)
				(island_removal_mode 0)
			)
			(polygon
				(pts
					(xy -0.635 -131.699) (xy -1.143 -131.699) (xy -1.143 -132.08) (xy -0.635 -132.08)
				)
			)
		)
	)
	(footprint ""
		(layer "B.Cu")
		(at 276.606 -26.868374 90)
		(property "Reference" "C4T4"
			(at 0 0 90)
			(layer "B.SilkS")
			(hide yes)
			(effects
				(font
					(size 1.27 1.27)
				)
				(justify mirror)
			)
		)
		(property "Value" ""
			(at 0 0 90)
			(layer "B.Fab")
			(effects
				(font
					(size 1.27 1.27)
				)
				(justify mirror)
			)
		)
		(duplicate_pad_numbers_are_jumpers no)
		(fp_rect
			(start 0.7239 1.9939)
			(end -0.7239 -0.2159)
			(stroke
				(width 0)
				(type default)
			)
			(fill no)
			(layer "B.CrtYd")
		)
		(fp_line
			(start 0.7239 -0.2159)
			(end 0.7239 1.9939)
			(stroke
				(width 0.1)
				(type default)
			)
			(layer "B.Fab")
		)
		(fp_line
			(start -0.7239 -0.2159)
			(end 0.7239 -0.2159)
			(stroke
				(width 0.1)
				(type default)
			)
			(layer "B.Fab")
		)
		(fp_line
			(start 0.7239 1.9939)
			(end -0.7239 1.9939)
			(stroke
				(width 0.1)
				(type default)
			)
			(layer "B.Fab")
		)
		(fp_line
			(start -0.7239 1.9939)
			(end -0.7239 -0.2159)
			(stroke
				(width 0.1)
				(type default)
			)
			(layer "B.Fab")
		)
		(pad "1" smd rect
			(at 0 0 270)
			(size 1.27 1.016)
			(layers "B.Cu" "B.Mask" "B.Paste")
			(net "PVDDQ_ABC")
		)
		(pad "2" smd rect
			(at 0 1.778 270)
			(size 1.27 1.016)
			(layers "B.Cu" "B.Mask" "B.Paste")
			(net "GND")
		)
		(zone
			(layer "B.Cu")
			(hatch none 0.5)
			(connect_pads
				(clearance 0)
			)
			(min_thickness 0.25)
			(keepout
				(tracks not_allowed)
				(vias allowed)
				(pads allowed)
				(copperpour not_allowed)
				(footprints allowed)
			)
			(placement
				(enabled no)
				(sheetname "")
			)
			(fill
				(thermal_gap 0.5)
				(thermal_bridge_width 0.5)
				(island_removal_mode 0)
			)
			(polygon
				(pts
					(xy 277.876 -27.503374) (xy 277.114 -27.503374) (xy 277.114 -26.233374) (xy 277.876 -26.233374)
				)
			)
		)
	)
)
